# T6G (Grand Teton) — schematic netlist excerpt (pin names and nets, part order shuffled) for the footprints in the layout excerpt that follows; sources: Cadence DE-HDL packaged netlist, KiCad conversion of 04192023_DAF0TMB3IC0_F0TG_MB_C_brd_V02_OCP.brd

PL27  Q_INDUCTOR  120NH/69A IND  pkg SMLF  page 213 : \1\ = GND ; \2\ = IND_CPU0_P1_CPL0
R1216  Q_RES  1K 1% CHIP  pkg 0201LF  page 186 : A = GND ; B = RT_ROM_MUX7_OE_N
R3868  Q_RES  0 5% CHIP  pkg 0402LF  page 140 : A = P12V_OCP_SENSE_2 ; B = P12V_OCP_V3_2_ISENSE_MAM_TIC

(kicad_pcb
	(version 20260206)
	(generator "pcbnew")
	(generator_version "10.0")
	(general
		(thickness 1.6)
		(legacy_teardrops no)
	)
	(paper "A4")
	(title_block
		(title "04192023_DAF0TMB3IC0_F0TG_MB_C_brd_V02_OCP.brd")
		(comment 1 "Grand Teton / footprints 4004-4006 of 8354")
	)
	(layers
		(0 "F.Cu" signal "TOP")
		(4 "In1.Cu" signal "GND")
		(6 "In2.Cu" signal "IN1")
		(8 "In3.Cu" signal "GND1")
		(10 "In4.Cu" signal "IN2")
		(12 "In5.Cu" signal "GND2")
		(14 "In6.Cu" signal "IN3")
		(16 "In7.Cu" signal "GND3")
		(18 "In8.Cu" signal "VCC")
		(20 "In9.Cu" signal "VCC1")
		(22 "In10.Cu" signal "GND4")
		(24 "In11.Cu" signal "IN4")
		(26 "In12.Cu" signal "GND5")
		(28 "In13.Cu" signal "IN5")
		(30 "In14.Cu" signal "GND6")
		(32 "In15.Cu" signal "IN6")
		(34 "In16.Cu" signal "GND7")
		(2 "B.Cu" signal "BOTTOM")
		(9 "F.Adhes" user "F.Adhesive")
		(11 "B.Adhes" user "B.Adhesive")
		(13 "F.Paste" user "Package Geometry/Pastemask Top")
		(15 "B.Paste" user "Package Geometry/Pastemask Bottom")
		(5 "F.SilkS" user "Ref Des/Silkscreen Top")
		(7 "B.SilkS" user "Ref Des/Silkscreen Bottom")
		(1 "F.Mask" user "Board Geometry/Soldermask Top")
		(3 "B.Mask" user "Board Geometry/Soldermask Bottom")
		(17 "Dwgs.User" user "User.Drawings")
		(19 "Cmts.User" user "User.Comments")
		(21 "Eco1.User" user "User.Eco1")
		(23 "Eco2.User" user "User.Eco2")
		(25 "Edge.Cuts" user "Board Geometry/Outline")
		(27 "Margin" user)
		(31 "F.CrtYd" user "Package Geometry/Place Bound Top")
		(29 "B.CrtYd" user "Package Geometry/Place Bound Bottom")
		(35 "F.Fab" user "Ref Des/Assembly Top")
		(33 "B.Fab" user "Ref Des/Assembly Bottom")
	)
	(footprint ""
		(layer "F.Cu")
		(at 57.901078 -175.823626 90)
		(property "Reference" "PL27"
			(at -4.994656 0.152908 0)
			(unlocked yes)
			(layer "F.SilkS")
			(effects
				(font
					(size 0.7874 0.5842)
					(thickness 0.1524)
				)
				(justify left)
			)
		)
		(property "Value" ""
			(at 0 0 90)
			(layer "F.Fab")
			(effects
				(font
					(size 1.27 1.27)
				)
			)
		)
		(duplicate_pad_numbers_are_jumpers no)
		(fp_line
			(start 3.24993 -3.24993)
			(end 3.24993 -2.2352)
			(stroke
				(width 0.1524)
				(type default)
			)
			(layer "F.SilkS")
		)
		(fp_line
			(start -3.24993 -3.24993)
			(end 3.24993 -3.24993)
			(stroke
				(width 0.1524)
				(type default)
			)
			(layer "F.SilkS")
		)
		(fp_line
			(start -3.24993 -2.2352)
			(end -3.24993 -3.24993)
			(stroke
				(width 0.1524)
				(type default)
			)
			(layer "F.SilkS")
		)
		(fp_line
			(start 3.24993 2.2352)
			(end 3.24993 3.24993)
			(stroke
				(width 0.1524)
				(type default)
			)
			(layer "F.SilkS")
		)
		(fp_line
			(start 3.24993 3.24993)
			(end -3.24993 3.24993)
			(stroke
				(width 0.1524)
				(type default)
			)
			(layer "F.SilkS")
		)
		(fp_line
			(start -3.24993 3.24993)
			(end -3.24993 2.2352)
			(stroke
				(width 0.1524)
				(type default)
			)
			(layer "F.SilkS")
		)
		(fp_line
			(start 3.24993 -3.24993)
			(end 3.24993 3.24993)
			(stroke
				(width 0.1)
				(type default)
			)
			(layer "F.Fab")
		)
		(fp_line
			(start -3.24993 -3.24993)
			(end 3.24993 -3.24993)
			(stroke
				(width 0.1)
				(type default)
			)
			(layer "F.Fab")
		)
		(fp_line
			(start 3.24993 3.24993)
			(end -3.24993 3.24993)
			(stroke
				(width 0.1)
				(type default)
			)
			(layer "F.Fab")
		)
		(fp_line
			(start -3.24993 3.24993)
			(end -3.24993 -3.24993)
			(stroke
				(width 0.1)
				(type default)
			)
			(layer "F.Fab")
		)
		(pad "1" smd rect
			(at -2.29997 0 90)
			(size 2.0066 4.2164)
			(layers "F.Cu" "F.Mask" "F.Paste")
			(net "GND")
		)
		(pad "2" smd rect
			(at 2.29997 0 90)
			(size 2.0066 4.2164)
			(layers "F.Cu" "F.Mask" "F.Paste")
			(net "IND_CPU0_P1_CPL0")
		)
	)
	(footprint ""
		(layer "F.Cu")
		(at 60.127388 -32.287972 180)
		(property "Reference" "R3868"
			(at 0 0 180)
			(layer "F.SilkS")
			(hide yes)
			(effects
				(font
					(size 1.27 1.27)
				)
			)
		)
		(property "Value" ""
			(at 0 0 180)
			(layer "F.Fab")
			(effects
				(font
					(size 1.27 1.27)
				)
			)
		)
		(duplicate_pad_numbers_are_jumpers no)
		(fp_line
			(start 0.7874 0.4064)
			(end -0.7874 0.4064)
			(stroke
				(width 0.1524)
				(type default)
			)
			(layer "F.SilkS")
		)
		(fp_line
			(start 0.7874 -0.4064)
			(end 0.7874 0.4064)
			(stroke
				(width 0.1524)
				(type default)
			)
			(layer "F.SilkS")
		)
		(fp_line
			(start -0.7874 0.4064)
			(end -0.7874 -0.4064)
			(stroke
				(width 0.1524)
				(type default)
			)
			(layer "F.SilkS")
		)
		(fp_line
			(start -0.7874 -0.4064)
			(end 0.7874 -0.4064)
			(stroke
				(width 0.1524)
				(type default)
			)
			(layer "F.SilkS")
		)
		(fp_line
			(start 0.67945 0.3048)
			(end 0.120396 0.3048)
			(stroke
				(width 0.1)
				(type default)
			)
			(layer "F.Fab")
		)
		(fp_line
			(start 0.67945 -0.3048)
			(end 0.67945 0.3048)
			(stroke
				(width 0.1)
				(type default)
			)
			(layer "F.Fab")
		)
		(fp_line
			(start 0.12065 -0.2794)
			(end 0.12065 -0.3048)
			(stroke
				(width 0.1)
				(type default)
			)
			(layer "F.Fab")
		)
		(fp_line
			(start 0.12065 -0.3048)
			(end 0.67945 -0.3048)
			(stroke
				(width 0.1)
				(type default)
			)
			(layer "F.Fab")
		)
		(fp_line
			(start 0.120396 0.3048)
			(end 0.120396 0.2794)
			(stroke
				(width 0.1)
				(type default)
			)
			(layer "F.Fab")
		)
		(fp_line
			(start 0.120396 0.2794)
			(end -0.12065 0.2794)
			(stroke
				(width 0.1)
				(type default)
			)
			(layer "F.Fab")
		)
		(fp_line
			(start -0.12065 0.3048)
			(end -0.67945 0.3048)
			(stroke
				(width 0.1)
				(type default)
			)
			(layer "F.Fab")
		)
		(fp_line
			(start -0.12065 0.2794)
			(end -0.12065 0.3048)
			(stroke
				(width 0.1)
				(type default)
			)
			(layer "F.Fab")
		)
		(fp_line
			(start -0.12065 -0.2794)
			(end 0.12065 -0.2794)
			(stroke
				(width 0.1)
				(type default)
			)
			(layer "F.Fab")
		)
		(fp_line
			(start -0.12065 -0.305054)
			(end -0.12065 -0.2794)
			(stroke
				(width 0.1)
				(type default)
			)
			(layer "F.Fab")
		)
		(fp_line
			(start -0.67945 0.3048)
			(end -0.67945 -0.305054)
			(stroke
				(width 0.1)
				(type default)
			)
			(layer "F.Fab")
		)
		(fp_line
			(start -0.67945 -0.305054)
			(end -0.12065 -0.305054)
			(stroke
				(width 0.1)
				(type default)
			)
			(layer "F.Fab")
		)
		(pad "1" smd rect
			(at -0.40005 0)
			(size 0.4572 0.508)
			(layers "F.Cu" "F.Mask" "F.Paste")
			(net "P12V_OCP_SENSE_2")
		)
		(pad "2" smd rect
			(at 0.40005 0)
			(size 0.4572 0.508)
			(layers "F.Cu" "F.Mask" "F.Paste")
			(net "P12V_OCP_V3_2_ISENSE_MAM_TIC")
		)
	)
	(footprint ""
		(layer "F.Cu")
		(at 372.237 -424.053 90)
		(property "Reference" "R1216"
			(at 0 0 90)
			(layer "F.SilkS")
			(hide yes)
			(effects
				(font
					(size 1.27 1.27)
				)
			)
		)
		(property "Value" ""
			(at 0 0 90)
			(layer "F.Fab")
			(effects
				(font
					(size 1.27 1.27)
				)
			)
		)
		(duplicate_pad_numbers_are_jumpers no)
		(fp_line
			(start 0.32512 -0.175006)
			(end 0.32512 0.175006)
			(stroke
				(width 0.1)
				(type default)
			)
			(layer "F.Fab")
		)
		(fp_line
			(start -0.32512 -0.175006)
			(end 0.32512 -0.175006)
			(stroke
				(width 0.1)
				(type default)
			)
			(layer "F.Fab")
		)
		(fp_line
			(start 0.32512 0.175006)
			(end -0.32512 0.175006)
			(stroke
				(width 0.1)
				(type default)
			)
			(layer "F.Fab")
		)
		(fp_line
			(start -0.32512 0.175006)
			(end -0.32512 -0.175006)
			(stroke
				(width 0.1)
				(type default)
			)
			(layer "F.Fab")
		)
		(pad "1" smd rect
			(at -0.2667 0 90)
			(size 0.3048 0.381)
			(layers "F.Cu" "F.Mask" "F.Paste")
			(net "GND")
		)
		(pad "2" smd rect
			(at 0.2667 0 270)
			(size 0.3048 0.381)
			(layers "F.Cu" "F.Mask" "F.Paste")
			(net "RT_ROM_MUX7_OE_N")
		)
	)
)
